FILE_TYPE = CONNECTIVITY;
{Allegro Design Entry HDL 16.6-p007 (v16-6-112F) 10/10/2012}
"PAGE_NUMBER" = 70;
0"NC";
1"PVCCMCP_CPU1\g";
2"PVCCMCP_CPU1\g";
3"PVCCMCP_CPU1\g";
4"TP_CPU1_RSVD_144";
5"TP_CPU1_RSVD_156";
6"TP_CPU1_RSVD_157";
7"TP_CPU1_RSVD_158";
8"TP_CPU1_RSVD_160";
9"TP_CPU1_RSVD_161";
10"TP_CPU1_RSVD_162";
11"TP_CPU1_RSVD_163";
12"TP_CPU1_RSVD_164";
13"TP_CPU1_RSVD_166";
14"TP_CPU1_RSVD_167";
15"TP_CPU1_RSVD_168";
16"TP_CPU1_RSVD_169";
17"TP_CPU1_RSVD_170";
18"TP_CPU1_RSVD_171";
19"TP_CPU1_RSVD_154";
20"TP_CPU1_RSVD_150";
21"TP_CPU1_RSVD_151";
22"TP_CPU1_RSVD_155";
23"TP_CPU1_RSVD_159";
24"TP_CPU1_RSVD_145";
25"TP_CPU1_RSVD_146";
26"TP_CPU1_RSVD_147";
27"TP_CPU1_RSVD_149";
28"TP_CPU1_RSVD_148";
29"TP_CPU1_RSVD_152";
30"CLK_100M_CPU1_RC_REFCLK1_DN";
31"CLK_100M_CPU1_RC_REFCLK1_DP";
32"TP_CPU1_RSVD_255";
33"TP_CPU1_RSVD_94";
34"TP_CPU1_RSVD_95";
35"TP_CPU1_RSVD_101";
36"TP_CPU1_RSVD_105";
37"TP_CPU1_RSVD_106";
38"TP_CPU1_RSVD_108";
39"TP_CPU1_RSVD_111";
40"TP_CPU1_RSVD_113";
41"TP_CPU1_RSVD_114";
42"TP_CPU1_RSVD_97";
43"TP_CPU1_RSVD_99";
44"TP_CPU1_RSVD_100";
45"TP_CPU1_RSVD_117";
46"TP_CPU1_RSVD_119";
47"TP_CPU1_RSVD_121";
48"TP_CPU1_RSVD_123";
49"TP_CPU1_RSVD_124";
50"TP_CPU1_TEST_9";
51"TP_CPU1_TEST_8";
52"TP_CPU1_TEST_7";
53"TP_CPU1_TEST_6";
54"TP_CPU1_TEST_10";
55"TP_CPU1_RSVD_82";
56"TP_CPU1_RSVD_85";
57"TP_CPU1_RSVD_90";
58"TP_CPU1_RSVD_91";
%"SKX_EXT_B"
"17","(-2925,2575)","0","chpset_lib","I10";
;
CDS_SEC"17"
CDS_LOCATION"U2D1"
SEC"17"
CDS_LIB"chpset_lib"
SEC_TYPE"BGA1"
PACK_TYPE"BGA1"
MATERIAL"IC"
PART_NUMBER"TBD"
LOCATION"U2D1";
"TEST_9"
$PN"AW20"50;
"TEST_8"
$PN"AW16"51;
"TEST_7"
$PN"AU18"52;
"TEST_6"
$PN"AR16"53;
"TEST_10"
$PN"AW22"54;
"RSVD<81>"
$PN"CL24"1;
"RSVD<82>"
$PN"CK77"55;
"RSVD<83>"
$PN"CK25"1;
"RSVD<84>"
$PN"CK23"1;
"RSVD<85>"
$PN"CK19"56;
"RSVD<86>"
$PN"CJ26"1;
"RSVD<87>"
$PN"CJ24"1;
"RSVD<88>"
$PN"CJ22"1;
"RSVD<89>"
$PN"CJ20"1;
"RSVD<90>"
$PN"CH77"57;
"RSVD<91>"
$PN"CH25"58;
%"VCC_CORE"
"1","(-1225,2825)","0","mstr_symbols","I12";
;
CDS_LIB"mstr_symbols"
HDL_POWER"PVCCMCP_CPU1";
"A"1;
%"VCC_CORE"
"1","(-4000,3775)","0","mstr_symbols","I13";
;
CDS_LIB"mstr_symbols"
HDL_POWER"PVCCMCP_CPU1";
"A"2;
%"VCC_CORE"
"1","(-7125,2350)","0","mstr_symbols","I15";
;
CDS_LIB"mstr_symbols"
HDL_POWER"PVCCMCP_CPU1";
"A"3;
%"SKX_EXT_B"
"16","(-5450,2550)","0","chpset_lib","I9";
;
CDS_SEC"16"
CDS_LOCATION"U2D1"
SEC"16"
CDS_LIB"chpset_lib"
SEC_TYPE"BGA1"
PACK_TYPE"BGA1"
MATERIAL"IC"
PART_NUMBER"TBD"
LOCATION"U2D1";
"RSVD<92>"
$PN"CH23"2;
"RSVD<93>"
$PN"CH21"2;
"RSVD<94>"
$PN"CG82"33;
"RSVD<95>"
$PN"CG78"34;
"RSVD<96>"
$PN"CG26"2;
"RSVD<97>"
$PN"CG24"42;
"RSVD<98>"
$PN"CG20"2;
"RSVD<99>"
$PN"CG10"43;
"RSVD<100>"
$PN"CF81"44;
"RSVD<101>"
$PN"CF79"35;
"RSVD<102>"
$PN"CF23"2;
"RSVD<103>"
$PN"CF21"2;
"RSVD<104>"
$PN"CF19"2;
"RSVD<105>"
$PN"CE80"36;
"RSVD<106>"
$PN"CE78"37;
"RSVD<107>"
$PN"CE22"2;
"RSVD<108>"
$PN"CD25"38;
"RSVD<109>"
$PN"CD21"2;
"RSVD<110>"
$PN"CD19"2;
"RSVD<111>"
$PN"CC6"39;
"RSVD<112>"
$PN"CC20"2;
"RSVD<113>"
$PN"CB5"40;
"RSVD<114>"
$PN"CB25"41;
"RSVD<115>"
$PN"CB21"2;
"RSVD<116>"
$PN"CB19"2;
"RSVD<117>"
$PN"CA24"45;
"RSVD<118>"
$PN"CA22"2;
"RSVD<119>"
$PN"BY25"46;
"RSVD<120>"
$PN"BY19"2;
"RSVD<121>"
$PN"BW22"47;
"RSVD<122>"
$PN"BW20"2;
"RSVD<123>"
$PN"BW10"48;
"RSVD<124>"
$PN"BV23"49;
"RSVD<125>"
$PN"BV21"2;
"RSVD<126>"
$PN"BV19"2;
"RSVD<127>"
$PN"BU22"3;
"RSVD<128>"
$PN"BU20"3;
"RSVD<129>"
$PN"BU18"3;
"RSVD<130>"
$PN"BR24"3;
"RSVD<131>"
$PN"BR22"3;
"RSVD<132>"
$PN"BP21"3;
"RSVD<133>"
$PN"BP17"3;
"RSVD<134>"
$PN"BN18"3;
"RSVD<135>"
$PN"BM19"3;
"RSVD<136>"
$PN"BM17"3;
"RSVD<137>"
$PN"BL20"3;
"RSVD<138>"
$PN"BL18"3;
"RSVD<139>"
$PN"BK17"3;
"RSVD<140>"
$PN"BJ20"3;
"RSVD<141>"
$PN"BJ18"3;
"RSVD<142>"
$PN"BJ16"3;
"RSVD<143>"
$PN"BH19"3;
"RSVD<144>"
$PN"BG20"4;
"RSVD<145>"
$PN"BG18"24;
"RSVD<146>"
$PN"BF21"25;
"RSVD<147>"
$PN"BE22"26;
"RSVD<148>"
$PN"BE20"28;
"RSVD<149>"
$PN"BE18"27;
"RSVD<150>"
$PN"BD69"20;
"RSVD<151>"
$PN"BD67"21;
"RSVD<152>"
$PN"BD65"29;
"RSVD<153>"
$PN"BD25"31;
"RSVD<154>"
$PN"BD19"19;
"RSVD<155>"
$PN"BD17"22;
"RSVD<156>"
$PN"BC68"5;
"RSVD<157>"
$PN"BC66"6;
"RSVD<158>"
$PN"BC64"7;
"RSVD<159>"
$PN"BC22"23;
"RSVD<160>"
$PN"BC20"8;
"RSVD<161>"
$PN"BC18"9;
"RSVD<162>"
$PN"BC14"10;
"RSVD<163>"
$PN"BB67"11;
"RSVD<164>"
$PN"BB65"12;
"RSVD<165>"
$PN"BB25"30;
"RSVD<166>"
$PN"BB21"13;
"RSVD<167>"
$PN"BB17"14;
"RSVD<168>"
$PN"BB15"15;
"RSVD<169>"
$PN"BB13"16;
"RSVD<170>"
$PN"BA82"17;
"RSVD<171>"
$PN"BA78"18;
"RSVD<255>"
$PN"AY83"32;
END.
